FILE_TYPE = MACRO_DRAWING;
SET COLOR_WIRE YELLOW;
SET COLOR_PROP ORANGE;
SET COLOR_DOT WHITE;
SET COLOR_ARC YELLOW;
SET COLOR_BODY GREEN;
SET COLOR_NOTE PURPLE;
SET PROP_DISPLAY VALUE;
SET PAGE_NUMBER P273;
FORCEADD QUANTA_TITLE_BLOCK_C..1
(0 0);
FORCEPROP 1 LAST CUSTOM_TXT_CDS <NAME_2>
J 0
(-3175 50);
FORCEPROP 1 LAST CUSTOM_TXT_CDS <NAME_1>
J 0
(-3175 175);
FORCEPROP 1 LAST CUSTOM_TXT_CDS <Q_NUMBER>
J 0
(-1403 103);
DISPLAY 1.212766 (-1403 103);
FORCEPROP 1 LAST CUSTOM_TXT_CDS <Q_PROJ>
J 0
(-2382 102);
DISPLAY 1.212766 (-2382 102);
FORCEPROP 1 LAST CUSTOM_TXT_CDS <Q_REV>
J 0
(-184 103);
DISPLAY 1.212766 (-184 103);
FORCEPROP 1 LAST CUSTOM_TXT_CDS <CON_LAST_MODIFIED>
J 0
(-1885 15);
DISPLAY 0.978723 (-1885 15);
FORCEPROP 1 LAST CUSTOM_TXT_CDS <CON_PAGE_NUM> OF <CON_TOTAL_PAGES>
J 0
(-446 18);
DISPLAY 0.978723 (-446 18);
FORCEPROP 1 LAST Q_TITLE P12V&P3V3 MOS SWITCH
J 0
(-9366 26);
DISPLAY 2.446809 (-9366 26);
PAINT GREEN (-9366 26);
FORCEPROP 1 LAST Q_DEPT BU9
J 1
(-3763 49);
DISPLAY 1.957447 (-3763 49);
PAINT GREEN (-3763 49);
FORCEPROP 1 LAST COMMENT_BODY TRUE
J 0
(12 -13);
DISPLAY 0.978723 (12 -13);
PAINT GREEN (12 -13);
DISPLAY INVISIBLE (12 -13);
FORCEPROP 1 LAST CDS_LMAN_SYM_OUTLINE -9475,6775,100,-125
J 0
(0 0);
DISPLAY 0.468085 (0 0);
PAINT GREEN (0 0);
DISPLAY INVISIBLE (0 0);
FORCEPROP 2 LAST CDS_LIB pure_quanta
J 0
(0 0);
DISPLAY INVISIBLE (0 0);
FORCEPROP 2 LAST PAGE_BORDER TRUE
J 0
(-7890 5250);
DISPLAY 0.638298 (-7890 5250);
PAINT PINK (-7890 5250);
DISPLAY INVISIBLE (-7890 5250);
FORCEPROP 2 LAST CDS_XR_PAGE_TITLE CR-161 : @T6G_MB_LIB.T6G(SCH_1):PAGE161
J 0
(-7890 5250);
DISPLAY 0.638298 (-7890 5250);
PAINT PINK (-7890 5250);
DISPLAY INVISIBLE (-7890 5250);
FORCEPROP 2 LAST CUSTOM_TXT_CDS <XR_PAGE_TITLE>
J 0
(-7890 5250);
DISPLAY 0.638298 (-7890 5250);
PAINT PINK (-7890 5250);
DISPLAY INVISIBLE (-7890 5250);
FORCEPROP 0 LAST CDS_CON_LAST_MODIFIED Wed Mar 09 21:31:54 2022
J 0
(-1885 15);
DISPLAY INVISIBLE (-1885 15);
QUIT
